# T6G (Grand Teton) — schematic netlist excerpt (pin names and nets, part order shuffled) for the footprints in the layout excerpt that follows; sources: Cadence DE-HDL packaged netlist, KiCad conversion of 04192023_DAF0TMB3IC0_F0TG_MB_C_brd_V02_OCP.brd

C6070  Q_CAP  0.01UF 50V 10% X7R  pkg C0402  page 177 : A = P1V2_AUX ; B = GND
R4152  Q_RES  33.2 1% CHIP  pkg 0402LF  page 151 : A = SMB_1_PLD_3V3AUX_SDA ; B = SMB_2_PLD_3V3AUX_SDA_R1
C6670  Q_CAP_DIFFBUS  DIFF BUS_0.22UF 6.3V 20% X6S  pkg C0201  page 330 : \1\ = P5E_CPU1_P1_TX_BUF_C_DN<4> ; \2\ = P5E_CPU1_P1_TX_BUF_DN<4>

(kicad_pcb
	(version 20260206)
	(generator "pcbnew")
	(generator_version "10.0")
	(general
		(thickness 1.6)
		(legacy_teardrops no)
	)
	(paper "A4")
	(title_block
		(title "04192023_DAF0TMB3IC0_F0TG_MB_C_brd_V02_OCP.brd")
		(comment 1 "Grand Teton / footprints 5319-5321 of 8354")
	)
	(layers
		(0 "F.Cu" signal "TOP")
		(4 "In1.Cu" signal "GND")
		(6 "In2.Cu" signal "IN1")
		(8 "In3.Cu" signal "GND1")
		(10 "In4.Cu" signal "IN2")
		(12 "In5.Cu" signal "GND2")
		(14 "In6.Cu" signal "IN3")
		(16 "In7.Cu" signal "GND3")
		(18 "In8.Cu" signal "VCC")
		(20 "In9.Cu" signal "VCC1")
		(22 "In10.Cu" signal "GND4")
		(24 "In11.Cu" signal "IN4")
		(26 "In12.Cu" signal "GND5")
		(28 "In13.Cu" signal "IN5")
		(30 "In14.Cu" signal "GND6")
		(32 "In15.Cu" signal "IN6")
		(34 "In16.Cu" signal "GND7")
		(2 "B.Cu" signal "BOTTOM")
		(9 "F.Adhes" user "F.Adhesive")
		(11 "B.Adhes" user "B.Adhesive")
		(13 "F.Paste" user "Package Geometry/Pastemask Top")
		(15 "B.Paste" user "Package Geometry/Pastemask Bottom")
		(5 "F.SilkS" user "Ref Des/Silkscreen Top")
		(7 "B.SilkS" user "Ref Des/Silkscreen Bottom")
		(1 "F.Mask" user "Board Geometry/Soldermask Top")
		(3 "B.Mask" user "Board Geometry/Soldermask Bottom")
		(17 "Dwgs.User" user "User.Drawings")
		(19 "Cmts.User" user "User.Comments")
		(21 "Eco1.User" user "User.Eco1")
		(23 "Eco2.User" user "User.Eco2")
		(25 "Edge.Cuts" user "Board Geometry/Outline")
		(27 "Margin" user)
		(31 "F.CrtYd" user "Package Geometry/Place Bound Top")
		(29 "B.CrtYd" user "Package Geometry/Place Bound Bottom")
		(35 "F.Fab" user "Ref Des/Assembly Top")
		(33 "B.Fab" user "Ref Des/Assembly Bottom")
	)
	(footprint ""
		(layer "B.Cu")
		(at 138.65352 -40.765222 180)
		(property "Reference" "C6070"
			(at 0 0 0)
			(layer "B.SilkS")
			(hide yes)
			(effects
				(font
					(size 1.27 1.27)
				)
				(justify mirror)
			)
		)
		(property "Value" ""
			(at 0 0 0)
			(layer "B.Fab")
			(effects
				(font
					(size 1.27 1.27)
				)
				(justify mirror)
			)
		)
		(duplicate_pad_numbers_are_jumpers no)
		(fp_line
			(start 0.7874 0.4064)
			(end 0.7874 -0.4064)
			(stroke
				(width 0.1524)
				(type default)
			)
			(layer "B.SilkS")
		)
		(fp_line
			(start 0.7874 -0.4064)
			(end -0.7874 -0.4064)
			(stroke
				(width 0.1524)
				(type default)
			)
			(layer "B.SilkS")
		)
		(fp_line
			(start -0.7874 0.4064)
			(end 0.7874 0.4064)
			(stroke
				(width 0.1524)
				(type default)
			)
			(layer "B.SilkS")
		)
		(fp_line
			(start -0.7874 -0.4064)
			(end -0.7874 0.4064)
			(stroke
				(width 0.1524)
				(type default)
			)
			(layer "B.SilkS")
		)
		(fp_line
			(start 0.67945 0.3048)
			(end 0.67945 -0.305054)
			(stroke
				(width 0.1)
				(type default)
			)
			(layer "B.Fab")
		)
		(fp_line
			(start 0.67945 -0.305054)
			(end 0.12065 -0.305054)
			(stroke
				(width 0.1)
				(type default)
			)
			(layer "B.Fab")
		)
		(fp_line
			(start 0.12065 0.3048)
			(end 0.67945 0.3048)
			(stroke
				(width 0.1)
				(type default)
			)
			(layer "B.Fab")
		)
		(fp_line
			(start 0.12065 0.2794)
			(end 0.12065 0.3048)
			(stroke
				(width 0.1)
				(type default)
			)
			(layer "B.Fab")
		)
		(fp_line
			(start 0.12065 -0.2794)
			(end -0.12065 -0.2794)
			(stroke
				(width 0.1)
				(type default)
			)
			(layer "B.Fab")
		)
		(fp_line
			(start 0.12065 -0.305054)
			(end 0.12065 -0.2794)
			(stroke
				(width 0.1)
				(type default)
			)
			(layer "B.Fab")
		)
		(fp_line
			(start -0.120396 0.3048)
			(end -0.120396 0.2794)
			(stroke
				(width 0.1)
				(type default)
			)
			(layer "B.Fab")
		)
		(fp_line
			(start -0.120396 0.2794)
			(end 0.12065 0.2794)
			(stroke
				(width 0.1)
				(type default)
			)
			(layer "B.Fab")
		)
		(fp_line
			(start -0.12065 -0.2794)
			(end -0.12065 -0.3048)
			(stroke
				(width 0.1)
				(type default)
			)
			(layer "B.Fab")
		)
		(fp_line
			(start -0.12065 -0.3048)
			(end -0.67945 -0.3048)
			(stroke
				(width 0.1)
				(type default)
			)
			(layer "B.Fab")
		)
		(fp_line
			(start -0.67945 0.3048)
			(end -0.120396 0.3048)
			(stroke
				(width 0.1)
				(type default)
			)
			(layer "B.Fab")
		)
		(fp_line
			(start -0.67945 -0.3048)
			(end -0.67945 0.3048)
			(stroke
				(width 0.1)
				(type default)
			)
			(layer "B.Fab")
		)
		(pad "1" smd circle
			(at 0.40005 0)
			(size 0 0)
			(layers "B.Cu" "B.Mask" "B.Paste")
			(net "P1V2_AUX")
		)
		(pad "2" smd circle
			(at -0.40005 0)
			(size 0 0)
			(layers "B.Cu" "B.Mask" "B.Paste")
			(net "GND")
		)
	)
	(footprint ""
		(layer "B.Cu")
		(at 160.69183 -16.77416)
		(property "Reference" "R4152"
			(at 0 0 0)
			(layer "B.SilkS")
			(hide yes)
			(effects
				(font
					(size 1.27 1.27)
				)
				(justify mirror)
			)
		)
		(property "Value" ""
			(at 0 0 0)
			(layer "B.Fab")
			(effects
				(font
					(size 1.27 1.27)
				)
				(justify mirror)
			)
		)
		(duplicate_pad_numbers_are_jumpers no)
		(fp_line
			(start -0.7874 -0.4064)
			(end -0.7874 0.4064)
			(stroke
				(width 0.1524)
				(type default)
			)
			(layer "B.SilkS")
		)
		(fp_line
			(start -0.7874 0.4064)
			(end 0.7874 0.4064)
			(stroke
				(width 0.1524)
				(type default)
			)
			(layer "B.SilkS")
		)
		(fp_line
			(start 0.7874 -0.4064)
			(end -0.7874 -0.4064)
			(stroke
				(width 0.1524)
				(type default)
			)
			(layer "B.SilkS")
		)
		(fp_line
			(start 0.7874 0.4064)
			(end 0.7874 -0.4064)
			(stroke
				(width 0.1524)
				(type default)
			)
			(layer "B.SilkS")
		)
		(fp_line
			(start -0.67945 -0.3048)
			(end -0.67945 0.3048)
			(stroke
				(width 0.1)
				(type default)
			)
			(layer "B.Fab")
		)
		(fp_line
			(start -0.67945 0.3048)
			(end -0.120396 0.3048)
			(stroke
				(width 0.1)
				(type default)
			)
			(layer "B.Fab")
		)
		(fp_line
			(start -0.12065 -0.3048)
			(end -0.67945 -0.3048)
			(stroke
				(width 0.1)
				(type default)
			)
			(layer "B.Fab")
		)
		(fp_line
			(start -0.12065 -0.2794)
			(end -0.12065 -0.3048)
			(stroke
				(width 0.1)
				(type default)
			)
			(layer "B.Fab")
		)
		(fp_line
			(start -0.120396 0.2794)
			(end 0.12065 0.2794)
			(stroke
				(width 0.1)
				(type default)
			)
			(layer "B.Fab")
		)
		(fp_line
			(start -0.120396 0.3048)
			(end -0.120396 0.2794)
			(stroke
				(width 0.1)
				(type default)
			)
			(layer "B.Fab")
		)
		(fp_line
			(start 0.12065 -0.305054)
			(end 0.12065 -0.2794)
			(stroke
				(width 0.1)
				(type default)
			)
			(layer "B.Fab")
		)
		(fp_line
			(start 0.12065 -0.2794)
			(end -0.12065 -0.2794)
			(stroke
				(width 0.1)
				(type default)
			)
			(layer "B.Fab")
		)
		(fp_line
			(start 0.12065 0.2794)
			(end 0.12065 0.3048)
			(stroke
				(width 0.1)
				(type default)
			)
			(layer "B.Fab")
		)
		(fp_line
			(start 0.12065 0.3048)
			(end 0.67945 0.3048)
			(stroke
				(width 0.1)
				(type default)
			)
			(layer "B.Fab")
		)
		(fp_line
			(start 0.67945 -0.305054)
			(end 0.12065 -0.305054)
			(stroke
				(width 0.1)
				(type default)
			)
			(layer "B.Fab")
		)
		(fp_line
			(start 0.67945 0.3048)
			(end 0.67945 -0.305054)
			(stroke
				(width 0.1)
				(type default)
			)
			(layer "B.Fab")
		)
		(pad "1" smd circle
			(at 0.40005 0 180)
			(size 0 0)
			(layers "B.Cu" "B.Mask" "B.Paste")
			(net "SMB_1_PLD_3V3AUX_SDA")
		)
		(pad "2" smd circle
			(at -0.40005 0 180)
			(size 0 0)
			(layers "B.Cu" "B.Mask" "B.Paste")
			(net "SMB_2_PLD_3V3AUX_SDA_R1")
		)
	)
	(footprint ""
		(layer "B.Cu")
		(at 61.553344 -408.517344 90)
		(property "Reference" "C6670"
			(at 0 0 90)
			(layer "B.SilkS")
			(hide yes)
			(effects
				(font
					(size 1.27 1.27)
				)
				(justify mirror)
			)
		)
		(property "Value" ""
			(at 0 0 90)
			(layer "B.Fab")
			(effects
				(font
					(size 1.27 1.27)
				)
				(justify mirror)
			)
		)
		(duplicate_pad_numbers_are_jumpers no)
		(fp_line
			(start 0.299974 -0.150114)
			(end -0.299974 -0.150114)
			(stroke
				(width 0.1)
				(type default)
			)
			(layer "B.Fab")
		)
		(fp_line
			(start -0.299974 -0.150114)
			(end -0.299974 0.150114)
			(stroke
				(width 0.1)
				(type default)
			)
			(layer "B.Fab")
		)
		(fp_line
			(start 0.299974 0.150114)
			(end 0.299974 -0.150114)
			(stroke
				(width 0.1)
				(type default)
			)
			(layer "B.Fab")
		)
		(fp_line
			(start -0.299974 0.150114)
			(end 0.299974 0.150114)
			(stroke
				(width 0.1)
				(type default)
			)
			(layer "B.Fab")
		)
		(pad "1" smd rect
			(at 0.2667 0 270)
			(size 0.3048 0.381)
			(layers "B.Cu" "B.Mask" "B.Paste")
			(net "P5E_CPU1_P1_TX_BUF_C_DN<4>")
		)
		(pad "2" smd rect
			(at -0.2667 0 270)
			(size 0.3048 0.381)
			(layers "B.Cu" "B.Mask" "B.Paste")
			(net "P5E_CPU1_P1_TX_BUF_DN<4>")
		)
	)
)
